(kicad_pcb
	(version 20260206)
	(generator "pcbnew")
	(generator_version "10.0")
	(general
		(thickness 1.6)
		(legacy_teardrops no)
	)
	(paper "A4")
	(title_block
		(title "03242023_DA0F0TMBIJ0_F0T_Motherboard_J_brd_V01_OCP.brd")
		(comment 1 "Grand Teton / footprints 182-187 of 6105")
	)
	(layers
		(0 "F.Cu" signal "TOP")
		(4 "In1.Cu" signal "GND")
		(6 "In2.Cu" signal "IN1")
		(8 "In3.Cu" signal "GND1")
		(10 "In4.Cu" signal "IN2")
		(12 "In5.Cu" signal "GND2")
		(14 "In6.Cu" signal "IN3")
		(16 "In7.Cu" signal "GND3")
		(18 "In8.Cu" signal "VCC")
		(20 "In9.Cu" signal "VCC1")
		(22 "In10.Cu" signal "GND4")
		(24 "In11.Cu" signal "IN4")
		(26 "In12.Cu" signal "GND5")
		(28 "In13.Cu" signal "IN5")
		(30 "In14.Cu" signal "GND6")
		(32 "In15.Cu" signal "IN6")
		(34 "In16.Cu" signal "GND7")
		(2 "B.Cu" signal "BOTTOM")
		(9 "F.Adhes" user "F.Adhesive")
		(11 "B.Adhes" user "B.Adhesive")
		(13 "F.Paste" user "Package Geometry/Pastemask Top")
		(15 "B.Paste" user "Package Geometry/Pastemask Bottom")
		(5 "F.SilkS" user "Ref Des/Silkscreen Top")
		(7 "B.SilkS" user "Ref Des/Silkscreen Bottom")
		(1 "F.Mask" user "Board Geometry/Soldermask Top")
		(3 "B.Mask" user "Board Geometry/Soldermask Bottom")
		(17 "Dwgs.User" user "User.Drawings")
		(19 "Cmts.User" user "User.Comments")
		(21 "Eco1.User" user "User.Eco1")
		(23 "Eco2.User" user "User.Eco2")
		(25 "Edge.Cuts" user "Board Geometry/Outline")
		(27 "Margin" user)
		(31 "F.CrtYd" user "Package Geometry/Place Bound Top")
		(29 "B.CrtYd" user "Package Geometry/Place Bound Bottom")
		(35 "F.Fab" user "Ref Des/Assembly Top")
		(33 "B.Fab" user "Ref Des/Assembly Bottom")
	)
	(footprint ""
		(layer "F.Cu")
		(at 419.91788 -156.632148 90)
		(property "Reference" "PR1779"
			(at 0 0 90)
			(layer "F.SilkS")
			(hide yes)
			(effects
				(font
					(size 1.27 1.27)
				)
			)
		)
		(property "Value" ""
			(at 0 0 90)
			(layer "F.Fab")
			(effects
				(font
					(size 1.27 1.27)
				)
			)
		)
		(duplicate_pad_numbers_are_jumpers no)
		(fp_line
			(start 0.7874 -0.4064)
			(end 0.7874 0.4064)
			(stroke
				(width 0.1524)
				(type default)
			)
			(layer "F.SilkS")
		)
		(fp_line
			(start -0.7874 -0.4064)
			(end 0.7874 -0.4064)
			(stroke
				(width 0.1524)
				(type default)
			)
			(layer "F.SilkS")
		)
		(fp_line
			(start 0.7874 0.4064)
			(end -0.7874 0.4064)
			(stroke
				(width 0.1524)
				(type default)
			)
			(layer "F.SilkS")
		)
		(fp_line
			(start -0.7874 0.4064)
			(end -0.7874 -0.4064)
			(stroke
				(width 0.1524)
				(type default)
			)
			(layer "F.SilkS")
		)
		(fp_line
			(start -0.12065 -0.305054)
			(end -0.12065 -0.2794)
			(stroke
				(width 0.1)
				(type default)
			)
			(layer "F.Fab")
		)
		(fp_line
			(start -0.67945 -0.305054)
			(end -0.12065 -0.305054)
			(stroke
				(width 0.1)
				(type default)
			)
			(layer "F.Fab")
		)
		(fp_line
			(start 0.67945 -0.3048)
			(end 0.67945 0.3048)
			(stroke
				(width 0.1)
				(type default)
			)
			(layer "F.Fab")
		)
		(fp_line
			(start 0.12065 -0.3048)
			(end 0.67945 -0.3048)
			(stroke
				(width 0.1)
				(type default)
			)
			(layer "F.Fab")
		)
		(fp_line
			(start 0.12065 -0.2794)
			(end 0.12065 -0.3048)
			(stroke
				(width 0.1)
				(type default)
			)
			(layer "F.Fab")
		)
		(fp_line
			(start -0.12065 -0.2794)
			(end 0.12065 -0.2794)
			(stroke
				(width 0.1)
				(type default)
			)
			(layer "F.Fab")
		)
		(fp_line
			(start 0.120396 0.2794)
			(end -0.12065 0.2794)
			(stroke
				(width 0.1)
				(type default)
			)
			(layer "F.Fab")
		)
		(fp_line
			(start -0.12065 0.2794)
			(end -0.12065 0.3048)
			(stroke
				(width 0.1)
				(type default)
			)
			(layer "F.Fab")
		)
		(fp_line
			(start 0.67945 0.3048)
			(end 0.120396 0.3048)
			(stroke
				(width 0.1)
				(type default)
			)
			(layer "F.Fab")
		)
		(fp_line
			(start 0.120396 0.3048)
			(end 0.120396 0.2794)
			(stroke
				(width 0.1)
				(type default)
			)
			(layer "F.Fab")
		)
		(fp_line
			(start -0.12065 0.3048)
			(end -0.67945 0.3048)
			(stroke
				(width 0.1)
				(type default)
			)
			(layer "F.Fab")
		)
		(fp_line
			(start -0.67945 0.3048)
			(end -0.67945 -0.305054)
			(stroke
				(width 0.1)
				(type default)
			)
			(layer "F.Fab")
		)
		(pad "1" smd circle
			(at -0.40005 0 90)
			(size 0 0)
			(layers "F.Cu" "F.Mask" "F.Paste")
			(net "PVCCFA_EHV_CPU0_NC1")
		)
		(pad "2" smd circle
			(at 0.40005 0 90)
			(size 0 0)
			(layers "F.Cu" "F.Mask" "F.Paste")
			(net "PVCCFA_EHV_CPU0_VDD1")
		)
	)
	(footprint ""
		(layer "F.Cu")
		(at 185.255662 -410.083762 180)
		(property "Reference" "PC2188"
			(at 0 0 180)
			(layer "F.SilkS")
			(hide yes)
			(effects
				(font
					(size 1.27 1.27)
				)
			)
		)
		(property "Value" ""
			(at 0 0 180)
			(layer "F.Fab")
			(effects
				(font
					(size 1.27 1.27)
				)
			)
		)
		(duplicate_pad_numbers_are_jumpers no)
		(fp_line
			(start 0.7874 0.4064)
			(end -0.7874 0.4064)
			(stroke
				(width 0.1524)
				(type default)
			)
			(layer "F.SilkS")
		)
		(fp_line
			(start 0.7874 -0.4064)
			(end 0.7874 0.4064)
			(stroke
				(width 0.1524)
				(type default)
			)
			(layer "F.SilkS")
		)
		(fp_line
			(start -0.7874 0.4064)
			(end -0.7874 -0.4064)
			(stroke
				(width 0.1524)
				(type default)
			)
			(layer "F.SilkS")
		)
		(fp_line
			(start -0.7874 -0.4064)
			(end 0.7874 -0.4064)
			(stroke
				(width 0.1524)
				(type default)
			)
			(layer "F.SilkS")
		)
		(fp_line
			(start 0.67945 0.3048)
			(end 0.120396 0.3048)
			(stroke
				(width 0.1)
				(type default)
			)
			(layer "F.Fab")
		)
		(fp_line
			(start 0.67945 -0.3048)
			(end 0.67945 0.3048)
			(stroke
				(width 0.1)
				(type default)
			)
			(layer "F.Fab")
		)
		(fp_line
			(start 0.12065 -0.2794)
			(end 0.12065 -0.3048)
			(stroke
				(width 0.1)
				(type default)
			)
			(layer "F.Fab")
		)
		(fp_line
			(start 0.12065 -0.3048)
			(end 0.67945 -0.3048)
			(stroke
				(width 0.1)
				(type default)
			)
			(layer "F.Fab")
		)
		(fp_line
			(start 0.120396 0.3048)
			(end 0.120396 0.2794)
			(stroke
				(width 0.1)
				(type default)
			)
			(layer "F.Fab")
		)
		(fp_line
			(start 0.120396 0.2794)
			(end -0.12065 0.2794)
			(stroke
				(width 0.1)
				(type default)
			)
			(layer "F.Fab")
		)
		(fp_line
			(start -0.12065 0.3048)
			(end -0.67945 0.3048)
			(stroke
				(width 0.1)
				(type default)
			)
			(layer "F.Fab")
		)
		(fp_line
			(start -0.12065 0.2794)
			(end -0.12065 0.3048)
			(stroke
				(width 0.1)
				(type default)
			)
			(layer "F.Fab")
		)
		(fp_line
			(start -0.12065 -0.2794)
			(end 0.12065 -0.2794)
			(stroke
				(width 0.1)
				(type default)
			)
			(layer "F.Fab")
		)
		(fp_line
			(start -0.12065 -0.305054)
			(end -0.12065 -0.2794)
			(stroke
				(width 0.1)
				(type default)
			)
			(layer "F.Fab")
		)
		(fp_line
			(start -0.67945 0.3048)
			(end -0.67945 -0.305054)
			(stroke
				(width 0.1)
				(type default)
			)
			(layer "F.Fab")
		)
		(fp_line
			(start -0.67945 -0.305054)
			(end -0.12065 -0.305054)
			(stroke
				(width 0.1)
				(type default)
			)
			(layer "F.Fab")
		)
		(pad "1" smd circle
			(at -0.40005 0 180)
			(size 0 0)
			(layers "F.Cu" "F.Mask" "F.Paste")
			(net "P12V_PSU")
		)
		(pad "2" smd circle
			(at 0.40005 0 180)
			(size 0 0)
			(layers "F.Cu" "F.Mask" "F.Paste")
			(net "GND")
		)
	)
	(footprint ""
		(layer "F.Cu")
		(at 175.82388 -19.548348 180)
		(property "Reference" "PC2238"
			(at 0 0 180)
			(layer "F.SilkS")
			(hide yes)
			(effects
				(font
					(size 1.27 1.27)
				)
			)
		)
		(property "Value" ""
			(at 0 0 180)
			(layer "F.Fab")
			(effects
				(font
					(size 1.27 1.27)
				)
			)
		)
		(duplicate_pad_numbers_are_jumpers no)
		(fp_line
			(start 0.7874 0.4064)
			(end -0.7874 0.4064)
			(stroke
				(width 0.1524)
				(type default)
			)
			(layer "F.SilkS")
		)
		(fp_line
			(start 0.7874 -0.4064)
			(end 0.7874 0.4064)
			(stroke
				(width 0.1524)
				(type default)
			)
			(layer "F.SilkS")
		)
		(fp_line
			(start -0.7874 0.4064)
			(end -0.7874 -0.4064)
			(stroke
				(width 0.1524)
				(type default)
			)
			(layer "F.SilkS")
		)
		(fp_line
			(start -0.7874 -0.4064)
			(end 0.7874 -0.4064)
			(stroke
				(width 0.1524)
				(type default)
			)
			(layer "F.SilkS")
		)
		(fp_line
			(start 0.67945 0.3048)
			(end 0.120396 0.3048)
			(stroke
				(width 0.1)
				(type default)
			)
			(layer "F.Fab")
		)
		(fp_line
			(start 0.67945 -0.3048)
			(end 0.67945 0.3048)
			(stroke
				(width 0.1)
				(type default)
			)
			(layer "F.Fab")
		)
		(fp_line
			(start 0.12065 -0.2794)
			(end 0.12065 -0.3048)
			(stroke
				(width 0.1)
				(type default)
			)
			(layer "F.Fab")
		)
		(fp_line
			(start 0.12065 -0.3048)
			(end 0.67945 -0.3048)
			(stroke
				(width 0.1)
				(type default)
			)
			(layer "F.Fab")
		)
		(fp_line
			(start 0.120396 0.3048)
			(end 0.120396 0.2794)
			(stroke
				(width 0.1)
				(type default)
			)
			(layer "F.Fab")
		)
		(fp_line
			(start 0.120396 0.2794)
			(end -0.12065 0.2794)
			(stroke
				(width 0.1)
				(type default)
			)
			(layer "F.Fab")
		)
		(fp_line
			(start -0.12065 0.3048)
			(end -0.67945 0.3048)
			(stroke
				(width 0.1)
				(type default)
			)
			(layer "F.Fab")
		)
		(fp_line
			(start -0.12065 0.2794)
			(end -0.12065 0.3048)
			(stroke
				(width 0.1)
				(type default)
			)
			(layer "F.Fab")
		)
		(fp_line
			(start -0.12065 -0.2794)
			(end 0.12065 -0.2794)
			(stroke
				(width 0.1)
				(type default)
			)
			(layer "F.Fab")
		)
		(fp_line
			(start -0.12065 -0.305054)
			(end -0.12065 -0.2794)
			(stroke
				(width 0.1)
				(type default)
			)
			(layer "F.Fab")
		)
		(fp_line
			(start -0.67945 0.3048)
			(end -0.67945 -0.305054)
			(stroke
				(width 0.1)
				(type default)
			)
			(layer "F.Fab")
		)
		(fp_line
			(start -0.67945 -0.305054)
			(end -0.12065 -0.305054)
			(stroke
				(width 0.1)
				(type default)
			)
			(layer "F.Fab")
		)
		(pad "1" smd circle
			(at -0.40005 0 180)
			(size 0 0)
			(layers "F.Cu" "F.Mask" "F.Paste")
			(net "P12V_SCM_R")
		)
		(pad "2" smd circle
			(at 0.40005 0 180)
			(size 0 0)
			(layers "F.Cu" "F.Mask" "F.Paste")
			(net "GND")
		)
	)
	(footprint ""
		(layer "F.Cu")
		(at 127.27432 -23.769828)
		(property "Reference" "C2286"
			(at 0 0 0)
			(layer "F.SilkS")
			(hide yes)
			(effects
				(font
					(size 1.27 1.27)
				)
			)
		)
		(property "Value" ""
			(at 0 0 0)
			(layer "F.Fab")
			(effects
				(font
					(size 1.27 1.27)
				)
			)
		)
		(duplicate_pad_numbers_are_jumpers no)
		(fp_line
			(start -0.7874 -0.4064)
			(end 0.7874 -0.4064)
			(stroke
				(width 0.1524)
				(type default)
			)
			(layer "F.SilkS")
		)
		(fp_line
			(start -0.7874 0.4064)
			(end -0.7874 -0.4064)
			(stroke
				(width 0.1524)
				(type default)
			)
			(layer "F.SilkS")
		)
		(fp_line
			(start 0.7874 -0.4064)
			(end 0.7874 0.4064)
			(stroke
				(width 0.1524)
				(type default)
			)
			(layer "F.SilkS")
		)
		(fp_line
			(start 0.7874 0.4064)
			(end -0.7874 0.4064)
			(stroke
				(width 0.1524)
				(type default)
			)
			(layer "F.SilkS")
		)
		(fp_line
			(start -0.67945 -0.305054)
			(end -0.12065 -0.305054)
			(stroke
				(width 0.1)
				(type default)
			)
			(layer "F.Fab")
		)
		(fp_line
			(start -0.67945 0.3048)
			(end -0.67945 -0.305054)
			(stroke
				(width 0.1)
				(type default)
			)
			(layer "F.Fab")
		)
		(fp_line
			(start -0.12065 -0.305054)
			(end -0.12065 -0.2794)
			(stroke
				(width 0.1)
				(type default)
			)
			(layer "F.Fab")
		)
		(fp_line
			(start -0.12065 -0.2794)
			(end 0.12065 -0.2794)
			(stroke
				(width 0.1)
				(type default)
			)
			(layer "F.Fab")
		)
		(fp_line
			(start -0.12065 0.2794)
			(end -0.12065 0.3048)
			(stroke
				(width 0.1)
				(type default)
			)
			(layer "F.Fab")
		)
		(fp_line
			(start -0.12065 0.3048)
			(end -0.67945 0.3048)
			(stroke
				(width 0.1)
				(type default)
			)
			(layer "F.Fab")
		)
		(fp_line
			(start 0.120396 0.2794)
			(end -0.12065 0.2794)
			(stroke
				(width 0.1)
				(type default)
			)
			(layer "F.Fab")
		)
		(fp_line
			(start 0.120396 0.3048)
			(end 0.120396 0.2794)
			(stroke
				(width 0.1)
				(type default)
			)
			(layer "F.Fab")
		)
		(fp_line
			(start 0.12065 -0.3048)
			(end 0.67945 -0.3048)
			(stroke
				(width 0.1)
				(type default)
			)
			(layer "F.Fab")
		)
		(fp_line
			(start 0.12065 -0.2794)
			(end 0.12065 -0.3048)
			(stroke
				(width 0.1)
				(type default)
			)
			(layer "F.Fab")
		)
		(fp_line
			(start 0.67945 -0.3048)
			(end 0.67945 0.3048)
			(stroke
				(width 0.1)
				(type default)
			)
			(layer "F.Fab")
		)
		(fp_line
			(start 0.67945 0.3048)
			(end 0.120396 0.3048)
			(stroke
				(width 0.1)
				(type default)
			)
			(layer "F.Fab")
		)
		(pad "1" smd circle
			(at -0.40005 0)
			(size 0 0)
			(layers "F.Cu" "F.Mask" "F.Paste")
			(net "P3V3_AUX_USB_BUF")
		)
		(pad "2" smd circle
			(at 0.40005 0)
			(size 0 0)
			(layers "F.Cu" "F.Mask" "F.Paste")
			(net "GND")
		)
	)
	(footprint ""
		(layer "F.Cu")
		(at 139.43838 -38.049708)
		(property "Reference" "C1880"
			(at 0 0 0)
			(layer "F.SilkS")
			(hide yes)
			(effects
				(font
					(size 1.27 1.27)
				)
			)
		)
		(property "Value" ""
			(at 0 0 0)
			(layer "F.Fab")
			(effects
				(font
					(size 1.27 1.27)
				)
			)
		)
		(duplicate_pad_numbers_are_jumpers no)
		(fp_line
			(start -0.7874 -0.4064)
			(end 0.7874 -0.4064)
			(stroke
				(width 0.1524)
				(type default)
			)
			(layer "F.SilkS")
		)
		(fp_line
			(start -0.7874 0.4064)
			(end -0.7874 -0.4064)
			(stroke
				(width 0.1524)
				(type default)
			)
			(layer "F.SilkS")
		)
		(fp_line
			(start 0.7874 -0.4064)
			(end 0.7874 0.4064)
			(stroke
				(width 0.1524)
				(type default)
			)
			(layer "F.SilkS")
		)
		(fp_line
			(start 0.7874 0.4064)
			(end -0.7874 0.4064)
			(stroke
				(width 0.1524)
				(type default)
			)
			(layer "F.SilkS")
		)
		(fp_line
			(start -0.67945 -0.305054)
			(end -0.12065 -0.305054)
			(stroke
				(width 0.1)
				(type default)
			)
			(layer "F.Fab")
		)
		(fp_line
			(start -0.67945 0.3048)
			(end -0.67945 -0.305054)
			(stroke
				(width 0.1)
				(type default)
			)
			(layer "F.Fab")
		)
		(fp_line
			(start -0.12065 -0.305054)
			(end -0.12065 -0.2794)
			(stroke
				(width 0.1)
				(type default)
			)
			(layer "F.Fab")
		)
		(fp_line
			(start -0.12065 -0.2794)
			(end 0.12065 -0.2794)
			(stroke
				(width 0.1)
				(type default)
			)
			(layer "F.Fab")
		)
		(fp_line
			(start -0.12065 0.2794)
			(end -0.12065 0.3048)
			(stroke
				(width 0.1)
				(type default)
			)
			(layer "F.Fab")
		)
		(fp_line
			(start -0.12065 0.3048)
			(end -0.67945 0.3048)
			(stroke
				(width 0.1)
				(type default)
			)
			(layer "F.Fab")
		)
		(fp_line
			(start 0.120396 0.2794)
			(end -0.12065 0.2794)
			(stroke
				(width 0.1)
				(type default)
			)
			(layer "F.Fab")
		)
		(fp_line
			(start 0.120396 0.3048)
			(end 0.120396 0.2794)
			(stroke
				(width 0.1)
				(type default)
			)
			(layer "F.Fab")
		)
		(fp_line
			(start 0.12065 -0.3048)
			(end 0.67945 -0.3048)
			(stroke
				(width 0.1)
				(type default)
			)
			(layer "F.Fab")
		)
		(fp_line
			(start 0.12065 -0.2794)
			(end 0.12065 -0.3048)
			(stroke
				(width 0.1)
				(type default)
			)
			(layer "F.Fab")
		)
		(fp_line
			(start 0.67945 -0.3048)
			(end 0.67945 0.3048)
			(stroke
				(width 0.1)
				(type default)
			)
			(layer "F.Fab")
		)
		(fp_line
			(start 0.67945 0.3048)
			(end 0.120396 0.3048)
			(stroke
				(width 0.1)
				(type default)
			)
			(layer "F.Fab")
		)
		(pad "1" smd circle
			(at -0.40005 0)
			(size 0 0)
			(layers "F.Cu" "F.Mask" "F.Paste")
			(net "P3V3_AUX")
		)
		(pad "2" smd circle
			(at 0.40005 0)
			(size 0 0)
			(layers "F.Cu" "F.Mask" "F.Paste")
			(net "GND")
		)
	)
	(footprint ""
		(layer "F.Cu")
		(at 104.347264 -238.162592 -90)
		(property "Reference" "C431"
			(at 0 0 270)
			(layer "F.SilkS")
			(hide yes)
			(effects
				(font
					(size 1.27 1.27)
				)
			)
		)
		(property "Value" ""
			(at 0 0 270)
			(layer "F.Fab")
			(effects
				(font
					(size 1.27 1.27)
				)
			)
		)
		(duplicate_pad_numbers_are_jumpers no)
		(fp_line
			(start -0.7874 0.4064)
			(end -0.7874 -0.4064)
			(stroke
				(width 0.1524)
				(type default)
			)
			(layer "F.SilkS")
		)
		(fp_line
			(start 0.7874 0.4064)
			(end -0.7874 0.4064)
			(stroke
				(width 0.1524)
				(type default)
			)
			(layer "F.SilkS")
		)
		(fp_line
			(start -0.7874 -0.4064)
			(end 0.7874 -0.4064)
			(stroke
				(width 0.1524)
				(type default)
			)
			(layer "F.SilkS")
		)
		(fp_line
			(start 0.7874 -0.4064)
			(end 0.7874 0.4064)
			(stroke
				(width 0.1524)
				(type default)
			)
			(layer "F.SilkS")
		)
		(fp_line
			(start -0.67945 0.3048)
			(end -0.67945 -0.305054)
			(stroke
				(width 0.1)
				(type default)
			)
			(layer "F.Fab")
		)
		(fp_line
			(start -0.12065 0.3048)
			(end -0.67945 0.3048)
			(stroke
				(width 0.1)
				(type default)
			)
			(layer "F.Fab")
		)
		(fp_line
			(start 0.120396 0.3048)
			(end 0.120396 0.2794)
			(stroke
				(width 0.1)
				(type default)
			)
			(layer "F.Fab")
		)
		(fp_line
			(start 0.67945 0.3048)
			(end 0.120396 0.3048)
			(stroke
				(width 0.1)
				(type default)
			)
			(layer "F.Fab")
		)
		(fp_line
			(start -0.12065 0.2794)
			(end -0.12065 0.3048)
			(stroke
				(width 0.1)
				(type default)
			)
			(layer "F.Fab")
		)
		(fp_line
			(start 0.120396 0.2794)
			(end -0.12065 0.2794)
			(stroke
				(width 0.1)
				(type default)
			)
			(layer "F.Fab")
		)
		(fp_line
			(start -0.12065 -0.2794)
			(end 0.12065 -0.2794)
			(stroke
				(width 0.1)
				(type default)
			)
			(layer "F.Fab")
		)
		(fp_line
			(start 0.12065 -0.2794)
			(end 0.12065 -0.3048)
			(stroke
				(width 0.1)
				(type default)
			)
			(layer "F.Fab")
		)
		(fp_line
			(start 0.12065 -0.3048)
			(end 0.67945 -0.3048)
			(stroke
				(width 0.1)
				(type default)
			)
			(layer "F.Fab")
		)
		(fp_line
			(start 0.67945 -0.3048)
			(end 0.67945 0.3048)
			(stroke
				(width 0.1)
				(type default)
			)
			(layer "F.Fab")
		)
		(fp_line
			(start -0.67945 -0.305054)
			(end -0.12065 -0.305054)
			(stroke
				(width 0.1)
				(type default)
			)
			(layer "F.Fab")
		)
		(fp_line
			(start -0.12065 -0.305054)
			(end -0.12065 -0.2794)
			(stroke
				(width 0.1)
				(type default)
			)
			(layer "F.Fab")
		)
		(pad "1" smd circle
			(at -0.40005 0 270)
			(size 0 0)
			(layers "F.Cu" "F.Mask" "F.Paste")
			(net "PVCCFA_EHV_FIVRA_CPU1")
		)
		(pad "2" smd circle
			(at 0.40005 0 270)
			(size 0 0)
			(layers "F.Cu" "F.Mask" "F.Paste")
			(net "GND")
		)
	)
)
